G04 ================== begin FILE IDENTIFICATION RECORD ==================*
G04 Layout Name:  D:/<user>/Wistron_project/16369-sd/gbr/16369-sd.brd*
G04 Film Name:    P_OUTLINE*
G04 File Format:  Gerber RS274X*
G04 File Origin:  Cadence Allegro 16.5-S056*
G04 Origin Date:  Wed Mar 29 13:12:39 2017*
G04 *
G04 Layer:  BOARD GEOMETRY/PANEL_OUTLINE*
G04 *
G04 Offset:    (0.00 0.00)*
G04 Mirror:    No*
G04 Mode:      Positive*
G04 Rotation:  0*
G04 FullContactRelief:  No*
G04 UndefLineWidth:     6.00*
G04 ================== end FILE IDENTIFICATION RECORD ====================*
%FSLAX35Y35*MOIN*%
%IR0*IPPOS*OFA0.00000B0.00000*MIA0B0*SFA1.00000B1.00000*%
%ADD10C,.006*%
G75*
%LPD*%
G75*
G54D10*
G01X-11811Y-26378D02*
G03X-7874Y-22441I0J3937D01*
G01X-31496Y-11378D02*
G03X-16496Y-26378I15000J0D01*
G01X0Y-18504D02*
G03X-7874I-3937J0D01*
G01X-11811Y-26378D02*
X-16496D01*
G01X-31496Y727913D02*
Y-11378D01*
G01X-7874Y-18504D02*
Y-22441D01*
G01Y20866D02*
G03X0I3937J0D01*
G01X-14607Y16741D02*
G03I-4291J0D01*
G01X-7874Y175427D02*
Y20866D01*
G01X-11608Y217029D02*
G03X-19685Y205824I3734J-11205D01*
G01X-9118Y209559D02*
G03X-11811Y205824I1244J-3735D01*
G01X-19685Y187877D02*
G03X-11608Y176672I11811J0D01*
G01X-11811Y187877D02*
G03X-9118Y184142I3937J0D01*
G01X-7874Y175427D02*
X-11609Y176672D01*
G01X-2692Y182000D02*
X-9119Y184142D01*
G01X-7874Y218273D02*
X-11609Y217029D01*
G01X-2692Y211701D02*
X-9119Y209559D01*
G01X-7874Y307086D02*
Y218273D01*
G01X-19685Y205824D02*
Y187877D01*
G01X-11811Y205824D02*
Y187877D01*
G01X0Y370079D02*
G03X-7874I-3937J0D01*
G01Y346456D02*
G03X0I3937J0D01*
G01Y307086D02*
G03X-7874I-3937J0D01*
G01Y370079D02*
Y346456D01*
G01Y409449D02*
G03X0I3937J0D01*
G01X-7874Y564010D02*
Y409449D01*
G01X-11608Y605612D02*
G03X-19685Y594406I3735J-11206D01*
G01X-9118Y598141D02*
G03X-11811Y594406I1244J-3735D01*
G01X-19685Y576459D02*
G03X-11608Y565254I11811J0D01*
G01X-11811Y576459D02*
G03X-9118Y572724I3937J0D01*
G01X-7874Y564010D02*
X-11609Y565255D01*
G01X-2692Y570582D02*
X-9119Y572725D01*
G01X-2692Y600284D02*
X-9119Y598141D01*
G01X-19685Y594406D02*
Y576459D01*
G01X-11811Y594406D02*
Y576459D01*
G01X-7874Y606856D02*
X-11609Y605611D01*
G01X-7874Y695669D02*
Y606856D01*
G01X-13215Y723144D02*
G03I-4291J0D01*
G01X-7874Y738976D02*
G03X-11811Y742913I-3937J0D01*
G01X-16496D02*
G03X-31496Y727913I0J-15000D01*
G01X-7874Y735039D02*
G03X0I3937J0D01*
G01Y695669D02*
G03X-7874I-3937J0D01*
G01X-11811Y742913D02*
X-16496D01*
G01X-7874Y738976D02*
Y735039D01*
G01X29075Y-26378D02*
G03X31044Y-24410I0J1969D01*
G01D02*
Y-788D01*
G01X0Y-22441D02*
G03X3937Y-26378I3937J0D01*
G01X0Y178265D02*
Y-22441D01*
G01X3937Y-26378D02*
X29075D01*
G01X44390Y5118D02*
G03I-2658J0D01*
G01X33012Y1181D02*
G03X31044Y-788I0J-1968D01*
G01X33012Y1181D02*
X199666D01*
G01X71407Y128987D02*
G03X76975Y134555I2784J2784D01*
G01X64567Y137457D02*
G03X65720Y134673I3938J0D01*
G01D02*
X94910Y105484D01*
G01X64567Y137457D02*
Y249131D01*
G01X-2692Y211701D02*
G03X0Y215436I-1245J3735D01*
G01Y178265D02*
G03X-2692Y182000I-3937J0D01*
G01X0Y350394D02*
Y215436D01*
G01X64567Y286302D02*
G03X67259Y282567I3937J0D01*
G01Y252866D02*
G03X64567Y249131I1245J-3735D01*
G01X73686Y280425D02*
X67259Y282567D01*
G01X64567Y286302D02*
Y350394D01*
G01X73686Y255008D02*
X67259Y252866D01*
G01X64567Y346456D02*
G03X72441I3937J0D01*
G01Y321260D02*
G03X64567I-3937J0D01*
G01X29075Y362205D02*
G03X31044Y364173I0J1969D01*
G01X0Y366142D02*
G03X3937Y362205I3937J0D01*
G01X31044Y364173D02*
Y387795D01*
G01X0Y566847D02*
Y366142D01*
G01X3937Y362205D02*
X29075D01*
G01X64567Y350394D02*
G03X60630Y354331I-3937J0D01*
G01X3937D02*
G03X0Y350394I0J-3937D01*
G01X60630Y354331D02*
X3937D01*
G01X44390Y393701D02*
G03I-2658J0D01*
G01X33012Y389764D02*
G03X31044Y387795I0J-1968D01*
G01X33012Y389764D02*
X199666D01*
G01X71407Y517570D02*
G03X76975Y523137I2784J2784D01*
G01X64567Y526040D02*
G03X65720Y523256I3938J0D01*
G01D02*
X94910Y494066D01*
G01X64567Y526040D02*
Y637713D01*
G01X-2692Y600283D02*
G03X0Y604019I-1245J3735D01*
G01Y566847D02*
G03X-2692Y570582I-3937J0D01*
G01X64567Y674885D02*
G03X67259Y671150I3937J0D01*
G01Y641448D02*
G03X64567Y637713I1245J-3735D01*
G01X73686Y669007D02*
X67259Y671150D01*
G01X64567Y674885D02*
Y738976D01*
G01X73686Y643591D02*
X67259Y641448D01*
G01X0Y738976D02*
Y604019D01*
G01X64567Y735039D02*
G03X72441I3937J0D01*
G01Y709842D02*
G03X64567I-3937J0D01*
G01Y738976D02*
G03X60630Y742913I-3937J0D01*
G01X3937D02*
G03X0Y738976I0J-3937D01*
G01X60630Y742913D02*
X3937D01*
G01X127362Y78740D02*
G03I-11023J0D01*
G01X118788Y137176D02*
G03I-4291J0D01*
G01X94791Y116738D02*
G03X89224Y111170I-2784J-2784D01*
G01X143454D02*
G03X137886Y116738I-2784J2784D01*
G01X134984Y104331D02*
G03X137768Y105484I0J3938D01*
G01X94910D02*
G03X97694Y104331I2784J2785D01*
G01X137886Y116738D02*
X133353Y112205D01*
G01X166957Y134673D02*
X137768Y105484D01*
G01X94791Y116738D02*
X99325Y112205D01*
G01X72441Y139088D02*
X76975Y134555D01*
G01X72441Y139088D02*
Y246293D01*
G01X133353Y112205D02*
X99325D01*
G01X134984Y104331D02*
X97694D01*
G01X84252Y276690D02*
G03X76175Y287895I-11811J0D01*
G01X76378Y276690D02*
G03X73686Y280425I-3937J0D01*
G01X76175Y247538D02*
G03X84252Y258743I-3734J11205D01*
G01X73686Y255008D02*
G03X76378Y258743I-1245J3735D01*
G01X76176Y287895D02*
X72441Y289140D01*
G01X84252Y258743D02*
Y276690D01*
G01X76378Y258743D02*
Y276690D01*
G01X72441Y289140D02*
Y321260D01*
G01X76176Y247538D02*
X72441Y246293D01*
G01X119874Y329366D02*
G03I-4291J0D01*
G01X76378Y354331D02*
G03X72441Y350394I0J-3937D01*
G01X76378Y354331D02*
X156299D01*
G01X72441Y346456D02*
Y350394D01*
G01X118788Y525759D02*
G03I-4291J0D01*
G01X94791Y505321D02*
G03X89224Y499753I-2784J-2784D01*
G01X143454D02*
G03X137886Y505321I-2784J2784D01*
G01D02*
X133353Y500787D01*
G01X94791Y505321D02*
X99325Y500787D01*
G01X72441Y527671D02*
X76975Y523137D01*
G01X133353Y500787D02*
X99325D01*
G01X134984Y492913D02*
G03X137768Y494066I0J3938D01*
G01X127362Y467323D02*
G03I-11023J0D01*
G01X94910Y494066D02*
G03X97694Y492913I2784J2785D01*
G01X166957Y523256D02*
X137768Y494066D01*
G01X134984Y492913D02*
X97694D01*
G01X72441Y527671D02*
Y634876D01*
G01X84252Y665272D02*
G03X76175Y676478I-11812J0D01*
G01Y636120D02*
G03X84252Y647326I-3735J11206D01*
G01X76176Y676477D02*
X72441Y677722D01*
G01X84252Y647326D02*
Y665272D01*
G01X72441Y677722D02*
Y709842D01*
G01X76176Y636121D02*
X72441Y634876D01*
G01X76378Y665272D02*
G03X73686Y669007I-3937J0D01*
G01Y643591D02*
G03X76378Y647326I-1245J3735D01*
G01D02*
Y665272D01*
G01X119874Y717948D02*
G03I-4291J0D01*
G01X76378Y742913D02*
G03X72441Y738976I0J-3937D01*
G01X76378Y742913D02*
X156299D01*
G01X72441Y735039D02*
Y738976D01*
G01X201634Y-24410D02*
G03X203603Y-26378I1968J0D01*
G01X201634Y-788D02*
Y-24410D01*
G01X203603Y-26378D02*
X228740D01*
G01X193603Y5118D02*
G03I-2658J0D01*
G01X201634Y-788D02*
G03X199666Y1181I-1969J0D01*
G01X155703Y134555D02*
G03X161271Y128987I2784J-2784D01*
G01X166957Y134673D02*
G03X168110Y137457I-2785J2784D01*
G01X160236Y139088D02*
X155703Y134555D01*
G01X160236Y246293D02*
Y139088D01*
G01X168110Y249131D02*
Y137457D01*
G01X165418Y282567D02*
G03X168110Y286302I-1245J3735D01*
G01X156502Y287895D02*
G03X148425Y276690I3734J-11205D01*
G01X158992Y280425D02*
G03X156299Y276690I1244J-3735D01*
G01X168110Y249131D02*
G03X165418Y252866I-3937J0D01*
G01X148425Y258743D02*
G03X156502Y247538I11811J0D01*
G01X156299Y258743D02*
G03X158992Y255008I3937J0D01*
G01X160236Y246293D02*
X156501Y247538D01*
G01X165418Y252866D02*
X158991Y255008D01*
G01X160236Y321260D02*
Y289140D01*
G01X168110Y350394D02*
Y286302D01*
G01X148425Y276690D02*
Y258743D01*
G01X156299Y276690D02*
Y258743D01*
G01X160236Y289140D02*
X156501Y287895D01*
G01X165418Y282567D02*
X158991Y280425D01*
G01X225227Y362205D02*
G03Y354331I0J-3937D01*
G01X207116D02*
G03Y362205I0J3937D01*
G01X160236Y346456D02*
G03X168110I3937J0D01*
G01Y321260D02*
G03X160236I-3937J0D01*
G01Y350394D02*
G03X156299Y354331I-3937J0D01*
G01X201634Y364173D02*
G03X203603Y362205I1968J0D01*
G01X201634Y387795D02*
Y364173D01*
G01X203603Y362205D02*
X228740D01*
G01X172047Y354331D02*
G03X168110Y350394I0J-3937D01*
G01X228740Y354331D02*
X172047D01*
G01X160236Y350394D02*
Y346456D01*
G01X193603Y393701D02*
G03I-2658J0D01*
G01X201634Y387795D02*
G03X199666Y389764I-1969J0D01*
G01X155703Y523137D02*
G03X161271Y517570I2784J-2783D01*
G01X160236Y527671D02*
X155703Y523137D01*
G01X166957Y523256D02*
G03X168110Y526040I-2785J2784D01*
G01Y637713D02*
Y526040D01*
G01X160236Y634876D02*
Y527671D01*
G01X156502Y676478D02*
G03X148425Y665272I3735J-11206D01*
G01Y647326D02*
G03X156502Y636120I11812J0D01*
G01X160236Y634876D02*
X156501Y636121D01*
G01X160236Y709842D02*
Y677722D01*
G01X148425Y665272D02*
Y647326D01*
G01X160236Y677722D02*
X156501Y676477D01*
G01X165418Y671150D02*
G03X168110Y674885I-1245J3735D01*
G01X158992Y669007D02*
G03X156299Y665272I1244J-3735D01*
G01X168110Y637713D02*
G03X165418Y641448I-3937J0D01*
G01X156299Y647326D02*
G03X158992Y643591I3937J0D01*
G01X165418Y641448D02*
X158991Y643591D01*
G01X168110Y738976D02*
Y674885D01*
G01X156299Y665272D02*
Y647326D01*
G01X165418Y671150D02*
X158991Y669007D01*
G01X160236Y735039D02*
G03X168110I3937J0D01*
G01Y709842D02*
G03X160236I-3937J0D01*
G01Y738976D02*
G03X156299Y742913I-3937J0D01*
G01X160236Y738976D02*
Y735039D01*
G01X172047Y742913D02*
G03X168110Y738976I0J-3937D01*
G01X228740Y742913D02*
X172047D01*
G01X236614Y-14567D02*
X244488D01*
G01X236614D02*
G03X232677Y-18504I0J-3937D01*
G01X248425D02*
G03X244488Y-14567I-3937J0D01*
G01X248425Y-22441D02*
G03X252362Y-26378I3937J0D01*
G01D02*
X309055D01*
G01X248425Y112921D02*
Y-22441D01*
G01X228740Y-26378D02*
G03X232677Y-22441I0J3937D01*
G01D02*
Y178669D01*
G01X236614Y16929D02*
X244488D01*
G01X232677Y20866D02*
G03X236614Y16929I3937J0D01*
G01X244488D02*
G03X248425Y20866I0J3937D01*
G01X246249Y145762D02*
G03X248425Y149283I-1761J3521D01*
G01Y112921D02*
G03X246249Y116442I-3937J0D01*
G01X242727Y144001D02*
G03X240551Y140480I1761J-3521D01*
G01Y121724D02*
G03X242727Y118203I3937J0D01*
G01X240551Y140480D02*
Y121724D01*
G01X242728Y118203D02*
X246249Y116442D01*
G01X242728Y144001D02*
X246249Y145762D01*
G01X248425Y350394D02*
Y149283D01*
G01X234853Y182190D02*
G03X232677Y178669I1761J-3521D01*
G01Y215031D02*
G03X234853Y211510I3937J0D01*
G01X238375Y183951D02*
G03X240551Y187472I-1761J3521D01*
G01Y206228D02*
G03X238375Y209749I-3937J0D01*
G01X240551Y187472D02*
Y206228D01*
G01X232677Y215031D02*
Y350394D01*
G01X238375Y209749D02*
X234854Y211510D01*
G01X238375Y183951D02*
X234854Y182190D01*
G01X273986Y362205D02*
G03Y354331I0J-3937D01*
G01X255876D02*
G03Y362205I0J3937D01*
G01X236614Y374016D02*
X244488D01*
G01X236614D02*
G03X232677Y370079I0J-3937D01*
G01X248425D02*
G03X244488Y374016I-3937J0D01*
G01X236614Y342519D02*
X244488D01*
G01X236614Y311023D02*
X244488D01*
G01X236614D02*
G03X232677Y307086I0J-3937D01*
G01Y346456D02*
G03X236614Y342519I3937J0D01*
G01X244488D02*
G03X248425Y346456I0J3937D01*
G01Y307086D02*
G03X244488Y311023I-3937J0D01*
G01X248425Y366142D02*
G03X252362Y362205I3937J0D01*
G01D02*
X309055D01*
G01X248425Y501504D02*
Y366142D01*
G01X228740Y362205D02*
G03X232677Y366142I0J3937D01*
G01D02*
Y567252D01*
G01X279469Y352362D02*
G03X277500Y354331I-1969J0D01*
G01X252362D02*
G03X248425Y350394I0J-3937D01*
G01X292815Y322834D02*
G03I-2657J0D01*
G01X279469Y328740D02*
G03X281437Y326771I1969J0D01*
G01X279469Y328740D02*
Y352362D01*
G01X448091Y326771D02*
X281437D01*
G01X277500Y354331D02*
X252362D01*
G01X232677Y350394D02*
G03X228740Y354331I-3937J0D01*
G01X236614Y405512D02*
X244488D01*
G01X232677Y409449D02*
G03X236614Y405512I3937J0D01*
G01X244488D02*
G03X248425Y409449I0J3937D01*
G01Y501504D02*
G03X246249Y505025I-3937J0D01*
G01X240551Y510307D02*
G03X242727Y506786I3937J0D01*
G01X240551Y529063D02*
Y510307D01*
G01X242728Y506786D02*
X246249Y505025D01*
G01Y534345D02*
G03X248425Y537866I-1761J3521D01*
G01X242727Y532584D02*
G03X240551Y529063I1761J-3521D01*
G01X248425Y738976D02*
Y537866D01*
G01X242728Y532584D02*
X246249Y534345D01*
G01X234853Y570773D02*
G03X232677Y567252I1761J-3521D01*
G01Y603614D02*
G03X234853Y600093I3937J0D01*
G01X238375Y572534D02*
G03X240551Y576055I-1761J3521D01*
G01Y594811D02*
G03X238375Y598332I-3937J0D01*
G01X240551Y576055D02*
Y594811D01*
G01X238375Y598332D02*
X234854Y600093D01*
G01X238375Y572534D02*
X234854Y570773D01*
G01X232677Y603614D02*
Y738976D01*
G01X236614Y731102D02*
X244488D01*
G01X236614Y699606D02*
X244488D01*
G01X236614D02*
G03X232677Y695669I0J-3937D01*
G01Y735039D02*
G03X236614Y731102I3937J0D01*
G01X244488D02*
G03X248425Y735039I0J3937D01*
G01Y695669D02*
G03X244488Y699606I-3937J0D01*
G01X279469Y740945D02*
G03X277500Y742913I-1968J0D01*
G01X252362D02*
G03X248425Y738976I0J-3937D01*
G01X292815Y711417D02*
G03I-2657J0D01*
G01X279469Y717323D02*
G03X281437Y715354I1969J0D01*
G01X279469Y717323D02*
Y740945D01*
G01X448091Y715354D02*
X281437D01*
G01X277500Y742913D02*
X252362D01*
G01X232677Y738976D02*
G03X228740Y742913I-3937J0D01*
G01X369811Y-1413D02*
G03I-4291J0D01*
G01X320866Y-18504D02*
G03X312992I-3937J0D01*
G01X320866Y-22441D02*
G03X324803Y-26378I3937J0D01*
G01X404725D02*
X324803D01*
G01X320866Y-22441D02*
Y-18504D01*
G01X309055Y-26378D02*
G03X312992Y-22441I0J3937D01*
G01D02*
Y41650D01*
G01Y6693D02*
G03X320866I3937J0D01*
G01X324600Y40057D02*
G03X332677Y51263I-3735J11206D01*
G01Y69209D02*
G03X324600Y80415I-11812J0D01*
G01X320866Y6693D02*
Y38813D01*
G01X332677Y51263D02*
Y69209D01*
G01X320866Y38813D02*
X324601Y40058D01*
G01X315685Y45385D02*
G03X312992Y41650I1244J-3735D01*
G01X322111Y47528D02*
G03X324803Y51263I-1245J3735D01*
G01Y69209D02*
G03X322111Y72944I-3937J0D01*
G01X324803Y51263D02*
Y69209D01*
G01X315684Y45385D02*
X322111Y47528D01*
G01X320866Y81659D02*
X324601Y80414D01*
G01X320866Y81659D02*
Y188864D01*
G01X312992Y78822D02*
G03X315685Y75087I3937J0D01*
G01X315684D02*
X322111Y72944D01*
G01X312992Y78822D02*
Y190495D01*
G01X370897Y190776D02*
G03I-4291J0D01*
G01X337649Y216782D02*
G03X343217Y211214I2784J-2784D01*
G01X325400Y193398D02*
G03X319832Y198965I-2784J2784D01*
G01X343217Y211214D02*
X347750Y215748D01*
G01X320866Y188864D02*
X325400Y193398D01*
G01X347750Y215748D02*
X381778D01*
G01X314145Y193279D02*
G03X312992Y190495I2785J-2784D01*
G01X346119Y223622D02*
G03X343335Y222469I0J-3938D01*
G01X314145Y193279D02*
X343335Y222469D01*
G01X375788Y249212D02*
G03I-11024J0D01*
G01X346119Y223622D02*
X383409D01*
G01X320866Y370079D02*
G03X312992I-3937J0D01*
G01X320866Y366142D02*
G03X324803Y362205I3937J0D01*
G01X404725D02*
X324803D01*
G01X320866Y366142D02*
Y370079D01*
G01X309055Y362205D02*
G03X312992Y366142I0J3937D01*
G01D02*
Y430233D01*
G01X369811Y387169D02*
G03I-4291J0D01*
G01X312992Y395275D02*
G03X320866I3937J0D01*
G01X324600Y428640D02*
G03X332677Y439845I-3734J11205D01*
G01X320866Y395275D02*
Y427395D01*
G01X332677Y439845D02*
Y457792D01*
G01X320866Y427395D02*
X324601Y428640D01*
G01X315685Y433968D02*
G03X312992Y430233I1244J-3735D01*
G01X322111Y436110D02*
G03X324803Y439845I-1245J3735D01*
G01D02*
Y457792D01*
G01X315684Y433968D02*
X322111Y436110D01*
G01X332677Y457792D02*
G03X324600Y468997I-11811J0D01*
G01X320866Y470242D02*
X324601Y468997D01*
G01X320866Y470242D02*
Y577447D01*
G01X312992Y467404D02*
G03X315685Y463669I3937J0D01*
G01X324803Y457792D02*
G03X322111Y461527I-3937J0D01*
G01X315684Y463669D02*
X322111Y461527D01*
G01X312992Y467404D02*
Y579078D01*
G01X370897Y579359D02*
G03I-4291J0D01*
G01X337649Y605365D02*
G03X343217Y599797I2784J-2784D01*
G01X325400Y581980D02*
G03X319832Y587548I-2784J2784D01*
G01X343217Y599797D02*
X347750Y604331D01*
G01X320866Y577447D02*
X325400Y581980D01*
G01X314145Y581862D02*
G03X312992Y579078I2785J-2784D01*
G01X314145Y581862D02*
X343335Y611051D01*
G01X347750Y604331D02*
X381778D01*
G01X346119Y612205D02*
G03X343335Y611051I1J-3937D01*
G01X375788Y637795D02*
G03I-11024J0D01*
G01X346119Y612205D02*
X383409D01*
G01X416536Y-18504D02*
G03X408662I-3937J0D01*
G01X404725Y-26378D02*
G03X408662Y-22441I0J3937D01*
G01Y-18504D02*
Y-22441D01*
G01X416536D02*
G03X420473Y-26378I3937J0D01*
G01D02*
X477166D01*
G01X416536Y41650D02*
Y-22441D01*
G01X408662Y6693D02*
G03X416536I3937J0D01*
G01X396851Y51263D02*
G03X404928Y40057I11812J0D01*
G01Y80415D02*
G03X396851Y69209I3735J-11206D01*
G01X404927Y40058D02*
X408662Y38813D01*
G01X396851Y69209D02*
Y51263D01*
G01X408662Y38813D02*
Y6693D01*
G01X416536Y41650D02*
G03X413843Y45385I-3937J0D01*
G01X404725Y51263D02*
G03X407417Y47528I3937J0D01*
G01Y72944D02*
G03X404725Y69209I1245J-3735D01*
G01X407417Y47528D02*
X413844Y45385D01*
G01X404725Y69209D02*
Y51263D01*
G01X408662Y188864D02*
Y81659D01*
G01X404927Y80414D02*
X408662Y81659D01*
G01X413843Y75087D02*
G03X416536Y78822I-1244J3735D01*
G01Y190495D02*
Y78822D01*
G01X407417Y72944D02*
X413844Y75087D01*
G01X409696Y198965D02*
G03X404128Y193398I-2784J-2783D01*
G01X386311Y211214D02*
G03X391879Y216782I2784J2784D01*
G01X386311Y211214D02*
X381778Y215748D01*
G01X408662Y188864D02*
X404128Y193398D01*
G01X386193Y222469D02*
G03X383409Y223622I-2784J-2785D01*
G01X416536Y190495D02*
G03X415383Y193279I-3938J0D01*
G01D02*
X386193Y222469D01*
G01X416536Y370079D02*
G03X408662I-3937J0D01*
G01X404725Y362205D02*
G03X408662Y366142I0J3937D01*
G01Y370079D02*
Y366142D01*
G01X416536D02*
G03X420473Y362205I3937J0D01*
G01D02*
X477166D01*
G01X416536Y430233D02*
Y366142D01*
G01X442028Y322834D02*
G03I-2658J0D01*
G01X448091Y326771D02*
G03X450059Y328740I0J1968D01*
G01X452028Y354331D02*
G03X450059Y352362I0J-1969D01*
G01D02*
Y328740D01*
G01X408662Y395275D02*
G03X416536I3937J0D01*
G01X396851Y439845D02*
G03X404928Y428640I11811J0D01*
G01X404927D02*
X408662Y427395D01*
G01X396851Y457792D02*
Y439845D01*
G01X408662Y427395D02*
Y395275D01*
G01X416536Y430233D02*
G03X413843Y433968I-3937J0D01*
G01X404725Y439845D02*
G03X407417Y436110I3937J0D01*
G01D02*
X413844Y433968D01*
G01X404725Y457792D02*
Y439845D01*
G01X404928Y468997D02*
G03X396851Y457792I3734J-11205D01*
G01X408662Y577447D02*
Y470242D01*
G01X404927Y468997D02*
X408662Y470242D01*
G01X413843Y463669D02*
G03X416536Y467404I-1244J3735D01*
G01X407417Y461527D02*
G03X404725Y457792I1245J-3735D01*
G01X416536Y579078D02*
Y467404D01*
G01X407417Y461527D02*
X413844Y463669D01*
G01X409696Y587548D02*
G03X404128Y581980I-2784J-2784D01*
G01X386311Y599797D02*
G03X391879Y605365I2784J2784D01*
G01X386311Y599797D02*
X381778Y604331D01*
G01X408662Y577447D02*
X404128Y581980D01*
G01X416536Y579078D02*
G03X415383Y581862I-3938J0D01*
G01D02*
X386193Y611051D01*
G01D02*
G03X383409Y612205I-2785J-2783D01*
G01X442028Y711417D02*
G03I-2658J0D01*
G01X448091Y715354D02*
G03X450059Y717323I0J1968D01*
G01X452028Y742913D02*
G03X450059Y740945I0J-1969D01*
G01D02*
Y717323D01*
G01X488977Y-22441D02*
G03X492914Y-26378I3937J0D01*
G01X497599D02*
G03X512599Y-11378I0J15000D01*
G01X488977Y-18504D02*
G03X481103I-3937J0D01*
G01X492914Y-26378D02*
X497599D01*
G01X512599Y-11378D02*
Y455139D01*
G01X488977Y-22441D02*
Y-18504D01*
G01X477166Y-26378D02*
G03X481103Y-22441I0J3937D01*
G01D02*
Y112517D01*
G01Y20866D02*
G03X488977I3937J0D01*
G01D02*
Y109679D01*
G01X492711Y110924D02*
G03X500788Y122129I-3734J11205D01*
G01Y140076D02*
G03X492711Y151281I-11811J0D01*
G01X488977Y109679D02*
X492712Y110924D01*
G01X500788Y122129D02*
Y140076D01*
G01X483795Y116252D02*
G03X481103Y112517I1245J-3735D01*
G01Y149688D02*
G03X483795Y145953I3937J0D01*
G01X490221Y118394D02*
G03X492914Y122129I-1244J3735D01*
G01Y140076D02*
G03X490221Y143811I-3937J0D01*
G01X483795Y145953D02*
X490222Y143811D01*
G01X483795Y116251D02*
X490222Y118394D01*
G01X492914Y122129D02*
Y140076D01*
G01X488977Y152525D02*
X492712Y151280D01*
G01X488977Y152525D02*
Y307086D01*
G01X481103Y149688D02*
Y350394D01*
G01X488977Y307086D02*
G03X481103I-3937J0D01*
G01Y346456D02*
G03X488977I3937J0D01*
G01Y370079D02*
G03X481103I-3937J0D01*
G01X488977Y346456D02*
Y370079D01*
G01X477166Y362205D02*
G03X481103Y366142I0J3937D01*
G01D02*
Y501099D01*
G01Y350394D02*
G03X477166Y354331I-3937J0D01*
G01D02*
X452028D01*
G01X481103Y409449D02*
G03X488977I3937J0D01*
G01D02*
Y498262D01*
G01X512599Y463013D02*
G03Y455139I0J-3937D01*
G01Y463013D02*
Y727913D01*
G01X492711Y499506D02*
G03X500788Y510711I-3734J11205D01*
G01X488977Y498262D02*
X492712Y499507D01*
G01X500788Y510711D02*
Y528658D01*
G01X483795Y504834D02*
G03X481103Y501099I1245J-3735D01*
G01X490221Y506976D02*
G03X492914Y510711I-1244J3735D01*
G01X483795Y504834D02*
X490222Y506976D01*
G01X492914Y510711D02*
Y528658D01*
G01X500788D02*
G03X492711Y539863I-11811J0D01*
G01X488977Y541108D02*
X492712Y539863D01*
G01X488977Y541108D02*
Y695669D01*
G01X481103Y538271D02*
G03X483795Y534535I3937J-1D01*
G01X492914Y528658D02*
G03X490221Y532393I-3937J0D01*
G01X483795Y534536D02*
X490222Y532393D01*
G01X481103Y538271D02*
Y738976D01*
G01X499107Y713716D02*
G03I-4291J0D01*
G01X492914Y742913D02*
G03X488977Y738976I0J-3937D01*
G01X512599Y727913D02*
G03X497599Y742913I-15000J0D01*
G01X488977Y695669D02*
G03X481103I-3937J0D01*
G01Y735039D02*
G03X488977I3937J0D01*
G01X492914Y742913D02*
X497599D01*
G01X488977Y735039D02*
Y738976D01*
G01X481103D02*
G03X477166Y742913I-3937J0D01*
G01D02*
X452028D01*
M02*
